(kicad_pcb
	(version 20260206)
	(generator "pcbnew")
	(generator_version "10.0")
	(general
		(thickness 1.6)
		(legacy_teardrops no)
	)
	(paper "A4")
	(title_block
		(title "03242023_DA0F0TMBIJ0_F0T_Motherboard_J_brd_V01_OCP.brd")
		(comment 1 "Grand Teton / footprint 2048 of 6105 (J3), pads 1-112 of 291")
	)
	(layers
		(0 "F.Cu" signal "TOP")
		(4 "In1.Cu" signal "GND")
		(6 "In2.Cu" signal "IN1")
		(8 "In3.Cu" signal "GND1")
		(10 "In4.Cu" signal "IN2")
		(12 "In5.Cu" signal "GND2")
		(14 "In6.Cu" signal "IN3")
		(16 "In7.Cu" signal "GND3")
		(18 "In8.Cu" signal "VCC")
		(20 "In9.Cu" signal "VCC1")
		(22 "In10.Cu" signal "GND4")
		(24 "In11.Cu" signal "IN4")
		(26 "In12.Cu" signal "GND5")
		(28 "In13.Cu" signal "IN5")
		(30 "In14.Cu" signal "GND6")
		(32 "In15.Cu" signal "IN6")
		(34 "In16.Cu" signal "GND7")
		(2 "B.Cu" signal "BOTTOM")
		(9 "F.Adhes" user "F.Adhesive")
		(11 "B.Adhes" user "B.Adhesive")
		(13 "F.Paste" user "Package Geometry/Pastemask Top")
		(15 "B.Paste" user "Package Geometry/Pastemask Bottom")
		(5 "F.SilkS" user "Ref Des/Silkscreen Top")
		(7 "B.SilkS" user "Ref Des/Silkscreen Bottom")
		(1 "F.Mask" user "Board Geometry/Soldermask Top")
		(3 "B.Mask" user "Board Geometry/Soldermask Bottom")
		(17 "Dwgs.User" user "User.Drawings")
		(19 "Cmts.User" user "User.Comments")
		(21 "Eco1.User" user "User.Eco1")
		(23 "Eco2.User" user "User.Eco2")
		(25 "Edge.Cuts" user "Board Geometry/Outline")
		(27 "Margin" user)
		(31 "F.CrtYd" user "Package Geometry/Place Bound Top")
		(29 "B.CrtYd" user "Package Geometry/Place Bound Bottom")
		(35 "F.Fab" user "Ref Des/Assembly Top")
		(33 "B.Fab" user "Ref Des/Assembly Bottom")
	)
	(footprint ""
		(layer "F.Cu")
		(at 288.305748 -258.091686)
		(property "Reference" "J3"
			(at -3.683 -81.702148 0)
			(unlocked yes)
			(layer "F.SilkS")
			(effects
				(font
					(size 0.7874 0.5842)
					(thickness 0.1524)
				)
				(justify left)
			)
		)
		(property "Value" ""
			(at 0 0 0)
			(layer "F.Fab")
			(effects
				(font
					(size 1.27 1.27)
				)
			)
		)
		(duplicate_pad_numbers_are_jumpers no)
		(pad "1" smd rect
			(at -2.050034 -63.324994 270)
			(size 0.519938 1.4986)
			(layers "F.Cu" "F.Mask" "F.Paste")
			(net "P12V_S3_AUX_CPU0_NVDIMM")
		)
		(pad "2" smd rect
			(at -2.050034 -62.47511 270)
			(size 0.519938 1.4986)
			(layers "F.Cu" "F.Mask" "F.Paste")
			(net "TP_CHB_CPU0_DIMM1_FRU_0")
		)
		(pad "3" smd rect
			(at -2.050034 -61.624972 270)
			(size 0.519938 1.4986)
			(layers "F.Cu" "F.Mask" "F.Paste")
			(net "P3V3_AUX")
		)
		(pad "4" smd rect
			(at -2.050034 -60.775088 270)
			(size 0.519938 1.4986)
			(layers "F.Cu" "F.Mask" "F.Paste")
			(net "I3C_SPD_DDRABCD_CPU0_LVC1_SCL_2")
		)
		(pad "5" smd rect
			(at -2.050034 -59.92495 270)
			(size 0.519938 1.4986)
			(layers "F.Cu" "F.Mask" "F.Paste")
			(net "I3C_SPD_DDRABCD_CPU0_LVC1_SDA")
		)
		(pad "6" smd rect
			(at -2.050034 -59.075066 270)
			(size 0.519938 1.4986)
			(layers "F.Cu" "F.Mask" "F.Paste")
			(net "GND")
		)
		(pad "7" smd rect
			(at -2.050034 -58.224928 270)
			(size 0.519938 1.4986)
			(layers "F.Cu" "F.Mask" "F.Paste")
			(net "M_B_CPU0_SA_DQ<0>")
		)
		(pad "8" smd rect
			(at -2.050034 -57.375044 270)
			(size 0.519938 1.4986)
			(layers "F.Cu" "F.Mask" "F.Paste")
			(net "GND")
		)
		(pad "9" smd rect
			(at -2.050034 -56.524906 270)
			(size 0.519938 1.4986)
			(layers "F.Cu" "F.Mask" "F.Paste")
			(net "M_B_CPU0_SA_DQ<1>")
		)
		(pad "10" smd rect
			(at -2.050034 -55.675022 270)
			(size 0.519938 1.4986)
			(layers "F.Cu" "F.Mask" "F.Paste")
			(net "GND")
		)
		(pad "11" smd rect
			(at -2.050034 -54.824884 270)
			(size 0.519938 1.4986)
			(layers "F.Cu" "F.Mask" "F.Paste")
			(net "M_B_CPU0_SA_DQS_DP<0>")
		)
		(pad "12" smd rect
			(at -2.050034 -53.975 270)
			(size 0.519938 1.4986)
			(layers "F.Cu" "F.Mask" "F.Paste")
			(net "M_B_CPU0_SA_DQS_DN<0>")
		)
		(pad "13" smd rect
			(at -2.050034 -53.125116 270)
			(size 0.519938 1.4986)
			(layers "F.Cu" "F.Mask" "F.Paste")
			(net "GND")
		)
		(pad "14" smd rect
			(at -2.050034 -52.274978 270)
			(size 0.519938 1.4986)
			(layers "F.Cu" "F.Mask" "F.Paste")
			(net "M_B_CPU0_SA_DQ<4>")
		)
		(pad "15" smd rect
			(at -2.050034 -51.425094 270)
			(size 0.519938 1.4986)
			(layers "F.Cu" "F.Mask" "F.Paste")
			(net "GND")
		)
		(pad "16" smd rect
			(at -2.050034 -50.574956 270)
			(size 0.519938 1.4986)
			(layers "F.Cu" "F.Mask" "F.Paste")
			(net "M_B_CPU0_SA_DQ<5>")
		)
		(pad "17" smd rect
			(at -2.050034 -49.725072 270)
			(size 0.519938 1.4986)
			(layers "F.Cu" "F.Mask" "F.Paste")
			(net "GND")
		)
		(pad "18" smd rect
			(at -2.050034 -48.874934 270)
			(size 0.519938 1.4986)
			(layers "F.Cu" "F.Mask" "F.Paste")
			(net "M_B_CPU0_SA_DQ<8>")
		)
		(pad "19" smd rect
			(at -2.050034 -48.02505 270)
			(size 0.519938 1.4986)
			(layers "F.Cu" "F.Mask" "F.Paste")
			(net "GND")
		)
		(pad "20" smd rect
			(at -2.050034 -47.174912 270)
			(size 0.519938 1.4986)
			(layers "F.Cu" "F.Mask" "F.Paste")
			(net "M_B_CPU0_SA_DQ<9>")
		)
		(pad "21" smd rect
			(at -2.050034 -46.325028 270)
			(size 0.519938 1.4986)
			(layers "F.Cu" "F.Mask" "F.Paste")
			(net "GND")
		)
		(pad "22" smd rect
			(at -2.050034 -45.47489 270)
			(size 0.519938 1.4986)
			(layers "F.Cu" "F.Mask" "F.Paste")
			(net "M_B_CPU0_SA_DQS_DP<1>")
		)
		(pad "23" smd rect
			(at -2.050034 -44.625006 270)
			(size 0.519938 1.4986)
			(layers "F.Cu" "F.Mask" "F.Paste")
			(net "M_B_CPU0_SA_DQS_DN<1>")
		)
		(pad "24" smd rect
			(at -2.050034 -43.775122 270)
			(size 0.519938 1.4986)
			(layers "F.Cu" "F.Mask" "F.Paste")
			(net "GND")
		)
		(pad "25" smd rect
			(at -2.050034 -42.924984 270)
			(size 0.519938 1.4986)
			(layers "F.Cu" "F.Mask" "F.Paste")
			(net "M_B_CPU0_SA_DQ<12>")
		)
		(pad "26" smd rect
			(at -2.050034 -42.0751 270)
			(size 0.519938 1.4986)
			(layers "F.Cu" "F.Mask" "F.Paste")
			(net "GND")
		)
		(pad "27" smd rect
			(at -2.050034 -41.224962 270)
			(size 0.519938 1.4986)
			(layers "F.Cu" "F.Mask" "F.Paste")
			(net "M_B_CPU0_SA_DQ<13>")
		)
		(pad "28" smd rect
			(at -2.050034 -40.375078 270)
			(size 0.519938 1.4986)
			(layers "F.Cu" "F.Mask" "F.Paste")
			(net "GND")
		)
		(pad "29" smd rect
			(at -2.050034 -39.52494 270)
			(size 0.519938 1.4986)
			(layers "F.Cu" "F.Mask" "F.Paste")
			(net "M_B_CPU0_SA_DQ<16>")
		)
		(pad "30" smd rect
			(at -2.050034 -38.675056 270)
			(size 0.519938 1.4986)
			(layers "F.Cu" "F.Mask" "F.Paste")
			(net "GND")
		)
		(pad "31" smd rect
			(at -2.050034 -37.824918 270)
			(size 0.519938 1.4986)
			(layers "F.Cu" "F.Mask" "F.Paste")
			(net "M_B_CPU0_SA_DQ<17>")
		)
		(pad "32" smd rect
			(at -2.050034 -36.975034 270)
			(size 0.519938 1.4986)
			(layers "F.Cu" "F.Mask" "F.Paste")
			(net "GND")
		)
		(pad "33" smd rect
			(at -2.050034 -36.124896 270)
			(size 0.519938 1.4986)
			(layers "F.Cu" "F.Mask" "F.Paste")
			(net "M_B_CPU0_SA_DQS_DP<2>")
		)
		(pad "34" smd rect
			(at -2.050034 -35.275012 270)
			(size 0.519938 1.4986)
			(layers "F.Cu" "F.Mask" "F.Paste")
			(net "M_B_CPU0_SA_DQS_DN<2>")
		)
		(pad "35" smd rect
			(at -2.050034 -34.425128 270)
			(size 0.519938 1.4986)
			(layers "F.Cu" "F.Mask" "F.Paste")
			(net "GND")
		)
		(pad "36" smd rect
			(at -2.050034 -33.57499 270)
			(size 0.519938 1.4986)
			(layers "F.Cu" "F.Mask" "F.Paste")
			(net "M_B_CPU0_SA_DQ<20>")
		)
		(pad "37" smd rect
			(at -2.050034 -32.725106 270)
			(size 0.519938 1.4986)
			(layers "F.Cu" "F.Mask" "F.Paste")
			(net "GND")
		)
		(pad "38" smd rect
			(at -2.050034 -31.874968 270)
			(size 0.519938 1.4986)
			(layers "F.Cu" "F.Mask" "F.Paste")
			(net "M_B_CPU0_SA_DQ<21>")
		)
		(pad "39" smd rect
			(at -2.050034 -31.025084 270)
			(size 0.519938 1.4986)
			(layers "F.Cu" "F.Mask" "F.Paste")
			(net "GND")
		)
		(pad "40" smd rect
			(at -2.050034 -30.174946 270)
			(size 0.519938 1.4986)
			(layers "F.Cu" "F.Mask" "F.Paste")
			(net "M_B_CPU0_SA_DQ<24>")
		)
		(pad "41" smd rect
			(at -2.050034 -29.325062 270)
			(size 0.519938 1.4986)
			(layers "F.Cu" "F.Mask" "F.Paste")
			(net "GND")
		)
		(pad "42" smd rect
			(at -2.050034 -28.474924 270)
			(size 0.519938 1.4986)
			(layers "F.Cu" "F.Mask" "F.Paste")
			(net "M_B_CPU0_SA_DQ<25>")
		)
		(pad "43" smd rect
			(at -2.050034 -27.62504 270)
			(size 0.519938 1.4986)
			(layers "F.Cu" "F.Mask" "F.Paste")
			(net "GND")
		)
		(pad "44" smd rect
			(at -2.050034 -26.774902 270)
			(size 0.519938 1.4986)
			(layers "F.Cu" "F.Mask" "F.Paste")
			(net "M_B_CPU0_SA_DQS_DP<3>")
		)
		(pad "45" smd rect
			(at -2.050034 -25.925018 270)
			(size 0.519938 1.4986)
			(layers "F.Cu" "F.Mask" "F.Paste")
			(net "M_B_CPU0_SA_DQS_DN<3>")
		)
		(pad "46" smd rect
			(at -2.050034 -25.07488 270)
			(size 0.519938 1.4986)
			(layers "F.Cu" "F.Mask" "F.Paste")
			(net "GND")
		)
		(pad "47" smd rect
			(at -2.050034 -24.224996 270)
			(size 0.519938 1.4986)
			(layers "F.Cu" "F.Mask" "F.Paste")
			(net "M_B_CPU0_SA_DQ<28>")
		)
		(pad "48" smd rect
			(at -2.050034 -23.375112 270)
			(size 0.519938 1.4986)
			(layers "F.Cu" "F.Mask" "F.Paste")
			(net "GND")
		)
		(pad "49" smd rect
			(at -2.050034 -22.524974 270)
			(size 0.519938 1.4986)
			(layers "F.Cu" "F.Mask" "F.Paste")
			(net "M_B_CPU0_SA_DQ<29>")
		)
		(pad "50" smd rect
			(at -2.050034 -21.67509 270)
			(size 0.519938 1.4986)
			(layers "F.Cu" "F.Mask" "F.Paste")
			(net "GND")
		)
		(pad "51" smd rect
			(at -2.050034 -20.824952 270)
			(size 0.519938 1.4986)
			(layers "F.Cu" "F.Mask" "F.Paste")
			(net "M_B_CPU0_SA_CB<0>")
		)
		(pad "52" smd rect
			(at -2.050034 -19.975068 270)
			(size 0.519938 1.4986)
			(layers "F.Cu" "F.Mask" "F.Paste")
			(net "GND")
		)
		(pad "53" smd rect
			(at -2.050034 -19.12493 270)
			(size 0.519938 1.4986)
			(layers "F.Cu" "F.Mask" "F.Paste")
			(net "M_B_CPU0_SA_CB<1>")
		)
		(pad "54" smd rect
			(at -2.050034 -18.275046 270)
			(size 0.519938 1.4986)
			(layers "F.Cu" "F.Mask" "F.Paste")
			(net "GND")
		)
		(pad "55" smd rect
			(at -2.050034 -17.424908 270)
			(size 0.519938 1.4986)
			(layers "F.Cu" "F.Mask" "F.Paste")
			(net "M_B_CPU0_SA_DQS_DP<4>")
		)
		(pad "56" smd rect
			(at -2.050034 -16.575024 270)
			(size 0.519938 1.4986)
			(layers "F.Cu" "F.Mask" "F.Paste")
			(net "M_B_CPU0_SA_DQS_DN<4>")
		)
		(pad "57" smd rect
			(at -2.050034 -15.724886 270)
			(size 0.519938 1.4986)
			(layers "F.Cu" "F.Mask" "F.Paste")
			(net "GND")
		)
		(pad "58" smd rect
			(at -2.050034 -14.875002 270)
			(size 0.519938 1.4986)
			(layers "F.Cu" "F.Mask" "F.Paste")
			(net "M_B_CPU0_SA_CB<4>")
		)
		(pad "59" smd rect
			(at -2.050034 -14.025118 270)
			(size 0.519938 1.4986)
			(layers "F.Cu" "F.Mask" "F.Paste")
			(net "GND")
		)
		(pad "60" smd rect
			(at -2.050034 -13.17498 270)
			(size 0.519938 1.4986)
			(layers "F.Cu" "F.Mask" "F.Paste")
			(net "M_B_CPU0_SA_CB<5>")
		)
		(pad "61" smd rect
			(at -2.050034 -12.325096 270)
			(size 0.519938 1.4986)
			(layers "F.Cu" "F.Mask" "F.Paste")
			(net "GND")
		)
		(pad "62" smd rect
			(at -2.050034 -11.474958 270)
			(size 0.519938 1.4986)
			(layers "F.Cu" "F.Mask" "F.Paste")
			(net "M_B_CPU0_ALERT_N")
		)
		(pad "63" smd rect
			(at -2.050034 -10.625074 270)
			(size 0.519938 1.4986)
			(layers "F.Cu" "F.Mask" "F.Paste")
			(net "GND")
		)
		(pad "64" smd rect
			(at -2.050034 -9.774936 270)
			(size 0.519938 1.4986)
			(layers "F.Cu" "F.Mask" "F.Paste")
			(net "M_B_CPU0_SA_CS_N<0>")
		)
		(pad "65" smd rect
			(at -2.050034 -8.925052 270)
			(size 0.519938 1.4986)
			(layers "F.Cu" "F.Mask" "F.Paste")
			(net "GND")
		)
		(pad "66" smd rect
			(at -2.050034 -8.074914 270)
			(size 0.519938 1.4986)
			(layers "F.Cu" "F.Mask" "F.Paste")
			(net "M_B_CPU0_SA_CA<0>")
		)
		(pad "67" smd rect
			(at -2.050034 -7.22503 270)
			(size 0.519938 1.4986)
			(layers "F.Cu" "F.Mask" "F.Paste")
			(net "GND")
		)
		(pad "68" smd rect
			(at -2.050034 -6.374892 270)
			(size 0.519938 1.4986)
			(layers "F.Cu" "F.Mask" "F.Paste")
			(net "M_B_CPU0_SA_CA<2>")
		)
		(pad "69" smd rect
			(at -2.050034 -5.525008 270)
			(size 0.519938 1.4986)
			(layers "F.Cu" "F.Mask" "F.Paste")
			(net "GND")
		)
		(pad "70" smd rect
			(at -2.050034 -4.675124 270)
			(size 0.519938 1.4986)
			(layers "F.Cu" "F.Mask" "F.Paste")
			(net "M_B_CPU0_SA_CA<4>")
		)
		(pad "71" smd rect
			(at -2.050034 -3.824986 270)
			(size 0.519938 1.4986)
			(layers "F.Cu" "F.Mask" "F.Paste")
			(net "GND")
		)
		(pad "72" smd rect
			(at -2.050034 -2.975102 270)
			(size 0.519938 1.4986)
			(layers "F.Cu" "F.Mask" "F.Paste")
			(net "M_B_CPU0_SA_CA<6>")
		)
		(pad "73" smd rect
			(at -2.050034 -2.124964 270)
			(size 0.519938 1.4986)
			(layers "F.Cu" "F.Mask" "F.Paste")
			(net "GND")
		)
		(pad "74" smd rect
			(at -2.050034 -1.27508 270)
			(size 0.519938 1.4986)
			(layers "F.Cu" "F.Mask" "F.Paste")
			(net "M_B_CPU0_SA_PAR")
		)
		(pad "75" smd rect
			(at -2.050034 -0.424942 270)
			(size 0.519938 1.4986)
			(layers "F.Cu" "F.Mask" "F.Paste")
			(net "GND")
		)
		(pad "76" smd rect
			(at -2.050034 5.525008 270)
			(size 0.519938 1.4986)
			(layers "F.Cu" "F.Mask" "F.Paste")
			(net "M_B_CPU0_SB_CA<0>")
		)
		(pad "77" smd rect
			(at -2.050034 6.374892 270)
			(size 0.519938 1.4986)
			(layers "F.Cu" "F.Mask" "F.Paste")
			(net "GND")
		)
		(pad "78" smd rect
			(at -2.050034 7.22503 270)
			(size 0.519938 1.4986)
			(layers "F.Cu" "F.Mask" "F.Paste")
			(net "M_B_CPU0_SB_CA<2>")
		)
		(pad "79" smd rect
			(at -2.050034 8.074914 270)
			(size 0.519938 1.4986)
			(layers "F.Cu" "F.Mask" "F.Paste")
			(net "GND")
		)
		(pad "80" smd rect
			(at -2.050034 8.925052 270)
			(size 0.519938 1.4986)
			(layers "F.Cu" "F.Mask" "F.Paste")
			(net "M_B_CPU0_SB_CA<4>")
		)
		(pad "81" smd rect
			(at -2.050034 9.774936 270)
			(size 0.519938 1.4986)
			(layers "F.Cu" "F.Mask" "F.Paste")
			(net "GND")
		)
		(pad "82" smd rect
			(at -2.050034 10.625074 270)
			(size 0.519938 1.4986)
			(layers "F.Cu" "F.Mask" "F.Paste")
			(net "M_B_CPU0_SB_CA<6>")
		)
		(pad "83" smd rect
			(at -2.050034 11.474958 270)
			(size 0.519938 1.4986)
			(layers "F.Cu" "F.Mask" "F.Paste")
			(net "GND")
		)
		(pad "84" smd rect
			(at -2.050034 12.325096 270)
			(size 0.519938 1.4986)
			(layers "F.Cu" "F.Mask" "F.Paste")
			(net "M_B_CPU0_SB_CS_N<0>")
		)
		(pad "85" smd rect
			(at -2.050034 13.17498 270)
			(size 0.519938 1.4986)
			(layers "F.Cu" "F.Mask" "F.Paste")
			(net "GND")
		)
		(pad "86" smd rect
			(at -2.050034 14.025118 270)
			(size 0.519938 1.4986)
			(layers "F.Cu" "F.Mask" "F.Paste")
			(net "M_B_CPU0_SA_RSP<0>")
		)
		(pad "87" smd rect
			(at -2.050034 14.875002 270)
			(size 0.519938 1.4986)
			(layers "F.Cu" "F.Mask" "F.Paste")
			(net "M_B_CPU0_SB_RSP<0>")
		)
		(pad "88" smd rect
			(at -2.050034 15.724886 270)
			(size 0.519938 1.4986)
			(layers "F.Cu" "F.Mask" "F.Paste")
			(net "GND")
		)
		(pad "89" smd rect
			(at -2.050034 16.575024 270)
			(size 0.519938 1.4986)
			(layers "F.Cu" "F.Mask" "F.Paste")
			(net "M_B_CPU0_SB_CB<4>")
		)
		(pad "90" smd rect
			(at -2.050034 17.424908 270)
			(size 0.519938 1.4986)
			(layers "F.Cu" "F.Mask" "F.Paste")
			(net "GND")
		)
		(pad "91" smd rect
			(at -2.050034 18.275046 270)
			(size 0.519938 1.4986)
			(layers "F.Cu" "F.Mask" "F.Paste")
			(net "M_B_CPU0_SB_CB<5>")
		)
		(pad "92" smd rect
			(at -2.050034 19.12493 270)
			(size 0.519938 1.4986)
			(layers "F.Cu" "F.Mask" "F.Paste")
			(net "GND")
		)
		(pad "93" smd rect
			(at -2.050034 19.975068 270)
			(size 0.519938 1.4986)
			(layers "F.Cu" "F.Mask" "F.Paste")
			(net "M_B_CPU0_SB_DQS_DP<9>")
		)
		(pad "94" smd rect
			(at -2.050034 20.824952 270)
			(size 0.519938 1.4986)
			(layers "F.Cu" "F.Mask" "F.Paste")
			(net "M_B_CPU0_SB_DQS_DN<9>")
		)
		(pad "95" smd rect
			(at -2.050034 21.67509 270)
			(size 0.519938 1.4986)
			(layers "F.Cu" "F.Mask" "F.Paste")
			(net "GND")
		)
		(pad "96" smd rect
			(at -2.050034 22.524974 270)
			(size 0.519938 1.4986)
			(layers "F.Cu" "F.Mask" "F.Paste")
			(net "M_B_CPU0_SB_CB<0>")
		)
		(pad "97" smd rect
			(at -2.050034 23.375112 270)
			(size 0.519938 1.4986)
			(layers "F.Cu" "F.Mask" "F.Paste")
			(net "GND")
		)
		(pad "98" smd rect
			(at -2.050034 24.224996 270)
			(size 0.519938 1.4986)
			(layers "F.Cu" "F.Mask" "F.Paste")
			(net "M_B_CPU0_SB_CB<1>")
		)
		(pad "99" smd rect
			(at -2.050034 25.07488 270)
			(size 0.519938 1.4986)
			(layers "F.Cu" "F.Mask" "F.Paste")
			(net "GND")
		)
		(pad "100" smd rect
			(at -2.050034 25.925018 270)
			(size 0.519938 1.4986)
			(layers "F.Cu" "F.Mask" "F.Paste")
			(net "M_B_CPU0_SB_DQ<0>")
		)
		(pad "101" smd rect
			(at -2.050034 26.774902 270)
			(size 0.519938 1.4986)
			(layers "F.Cu" "F.Mask" "F.Paste")
			(net "GND")
		)
		(pad "102" smd rect
			(at -2.050034 27.62504 270)
			(size 0.519938 1.4986)
			(layers "F.Cu" "F.Mask" "F.Paste")
			(net "M_B_CPU0_SB_DQ<1>")
		)
		(pad "103" smd rect
			(at -2.050034 28.474924 270)
			(size 0.519938 1.4986)
			(layers "F.Cu" "F.Mask" "F.Paste")
			(net "GND")
		)
		(pad "104" smd rect
			(at -2.050034 29.325062 270)
			(size 0.519938 1.4986)
			(layers "F.Cu" "F.Mask" "F.Paste")
			(net "M_B_CPU0_SB_DQS_DP<0>")
		)
		(pad "105" smd rect
			(at -2.050034 30.174946 270)
			(size 0.519938 1.4986)
			(layers "F.Cu" "F.Mask" "F.Paste")
			(net "M_B_CPU0_SB_DQS_DN<0>")
		)
		(pad "106" smd rect
			(at -2.050034 31.025084 270)
			(size 0.519938 1.4986)
			(layers "F.Cu" "F.Mask" "F.Paste")
			(net "GND")
		)
		(pad "107" smd rect
			(at -2.050034 31.874968 270)
			(size 0.519938 1.4986)
			(layers "F.Cu" "F.Mask" "F.Paste")
			(net "M_B_CPU0_SB_DQ<4>")
		)
		(pad "108" smd rect
			(at -2.050034 32.725106 270)
			(size 0.519938 1.4986)
			(layers "F.Cu" "F.Mask" "F.Paste")
			(net "GND")
		)
		(pad "109" smd rect
			(at -2.050034 33.57499 270)
			(size 0.519938 1.4986)
			(layers "F.Cu" "F.Mask" "F.Paste")
			(net "M_B_CPU0_SB_DQ<5>")
		)
		(pad "110" smd rect
			(at -2.050034 34.425128 270)
			(size 0.519938 1.4986)
			(layers "F.Cu" "F.Mask" "F.Paste")
			(net "GND")
		)
		(pad "111" smd rect
			(at -2.050034 35.275012 270)
			(size 0.519938 1.4986)
			(layers "F.Cu" "F.Mask" "F.Paste")
			(net "M_B_CPU0_SB_DQ<8>")
		)
		(pad "112" smd rect
			(at -2.050034 36.124896 270)
			(size 0.519938 1.4986)
			(layers "F.Cu" "F.Mask" "F.Paste")
			(net "GND")
		)
	)
)
